(kicad_pcb
	(version 20260206)
	(generator "pcbnew")
	(generator_version "10.0")
	(general
		(thickness 1.6)
		(legacy_teardrops no)
	)
	(paper "A4")
	(title_block
		(title "Bryce Canyon_F.DPB_16315-1-OCP.brd")
		(comment 1 "Bryce Canyon / footprints 585-593 of 2223")
	)
	(layers
		(0 "F.Cu" signal "TOP")
		(4 "In1.Cu" signal "L2GND")
		(6 "In2.Cu" signal "L3")
		(8 "In3.Cu" signal "L4GND")
		(10 "In4.Cu" signal "L5")
		(12 "In5.Cu" signal "L6VCC")
		(14 "In6.Cu" signal "L7VCC")
		(16 "In7.Cu" signal "L8")
		(18 "In8.Cu" signal "L9GND")
		(20 "In9.Cu" signal "L10")
		(22 "In10.Cu" signal "L11GND")
		(2 "B.Cu" signal "BOTTOM")
		(9 "F.Adhes" user "F.Adhesive")
		(11 "B.Adhes" user "B.Adhesive")
		(13 "F.Paste" user "Package Geometry/Pastemask Top")
		(15 "B.Paste" user "Package Geometry/Pastemask Bottom")
		(5 "F.SilkS" user "Ref Des/Silkscreen Top")
		(7 "B.SilkS" user "Ref Des/Silkscreen Bottom")
		(1 "F.Mask" user "Board Geometry/Soldermask Top")
		(3 "B.Mask" user "Board Geometry/Soldermask Bottom")
		(17 "Dwgs.User" user "User.Drawings")
		(19 "Cmts.User" user "User.Comments")
		(21 "Eco1.User" user "User.Eco1")
		(23 "Eco2.User" user "User.Eco2")
		(25 "Edge.Cuts" user "Board Geometry/Outline")
		(27 "Margin" user)
		(31 "F.CrtYd" user "Package Geometry/Place Bound Top")
		(29 "B.CrtYd" user "Package Geometry/Place Bound Bottom")
		(35 "F.Fab" user "Ref Des/Assembly Top")
		(33 "B.Fab" user "Ref Des/Assembly Bottom")
	)
	(footprint ""
		(layer "F.Cu")
		(at 267.18641 -131.636262 -90)
		(property "Reference" "TP185"
			(at 0 0 270)
			(layer "F.SilkS")
			(hide yes)
			(effects
				(font
					(size 1.27 1.27)
				)
			)
		)
		(property "Value" "TPAD32-GP"
			(at -0.0508 -1.6764 270)
			(unlocked yes)
			(layer "F.Fab")
			(hide yes)
			(effects
				(font
					(size 1.016 1.016)
					(thickness 0.1524)
				)
			)
		)
		(property "Device Type" "TPAD32"
			(at -0.0508 -3.2004 270)
			(unlocked yes)
			(layer "F.Fab")
			(hide yes)
			(effects
				(font
					(size 1.016 1.016)
					(thickness 0.1524)
				)
			)
		)
		(duplicate_pad_numbers_are_jumpers no)
		(fp_poly
			(pts
				(arc
					(start 0 -0.4064)
					(mid 0 0.4064)
					(end 0 -0.4064)
				)
			)
			(stroke
				(width 0)
				(type default)
			)
			(fill no)
			(layer "F.CrtYd")
		)
		(fp_poly
			(pts
				(arc
					(start 0 -0.7112)
					(mid 0 0.7112)
					(end 0 -0.7112)
				)
			)
			(stroke
				(width 0)
				(type default)
			)
			(fill no)
			(layer "F.Fab")
		)
		(pad "1" smd circle
			(at 0 0 270)
			(size 0.8128 0.8128)
			(layers "F.Cu" "F.Mask" "F.Paste")
			(net "TP_COMP_B_SATA_P0_RX_DP")
		)
	)
	(footprint ""
		(layer "F.Cu")
		(at 67.1068 -298.704)
		(property "Reference" "TP7"
			(at 0 0 0)
			(layer "F.SilkS")
			(hide yes)
			(effects
				(font
					(size 1.27 1.27)
				)
			)
		)
		(property "Value" "TPAD32-GP"
			(at -0.0508 -1.6764 0)
			(unlocked yes)
			(layer "F.Fab")
			(hide yes)
			(effects
				(font
					(size 1.016 1.016)
					(thickness 0.1524)
				)
			)
		)
		(property "Device Type" "TPAD32"
			(at -0.0508 -3.2004 0)
			(unlocked yes)
			(layer "F.Fab")
			(hide yes)
			(effects
				(font
					(size 1.016 1.016)
					(thickness 0.1524)
				)
			)
		)
		(duplicate_pad_numbers_are_jumpers no)
		(fp_poly
			(pts
				(arc
					(start 0.4064 0)
					(mid -0.4064 0)
					(end 0.4064 0)
				)
			)
			(stroke
				(width 0)
				(type default)
			)
			(fill no)
			(layer "F.CrtYd")
		)
		(fp_poly
			(pts
				(arc
					(start 0.7112 0)
					(mid -0.7112 0)
					(end 0.7112 0)
				)
			)
			(stroke
				(width 0)
				(type default)
			)
			(fill no)
			(layer "F.Fab")
		)
		(pad "1" smd circle
			(at 0 0)
			(size 0.8128 0.8128)
			(layers "F.Cu" "F.Mask" "F.Paste")
			(net "ACT_HDD_1")
		)
	)
	(footprint ""
		(layer "F.Cu")
		(at 224.14103 -357.961438)
		(property "Reference" "R426"
			(at 0 0 0)
			(layer "F.SilkS")
			(hide yes)
			(effects
				(font
					(size 1.27 1.27)
				)
			)
		)
		(property "Value" "1KR2F-3-GP"
			(at 0.064008 -3.993896 0)
			(unlocked yes)
			(layer "F.Fab")
			(hide yes)
			(effects
				(font
					(size 1.016 1.016)
					(thickness 0.1524)
				)
			)
		)
		(property "Device Type" "R402H16"
			(at 0.064008 -5.517896 0)
			(unlocked yes)
			(layer "F.Fab")
			(hide yes)
			(effects
				(font
					(size 1.016 1.016)
					(thickness 0.1524)
				)
			)
		)
		(duplicate_pad_numbers_are_jumpers no)
		(fp_line
			(start -0.508 -0.9398)
			(end -0.508 0.9398)
			(stroke
				(width 0.1524)
				(type default)
			)
			(layer "F.SilkS")
		)
		(fp_line
			(start 0.508 -0.9398)
			(end -0.508 -0.9398)
			(stroke
				(width 0.1524)
				(type default)
			)
			(layer "F.SilkS")
		)
		(fp_rect
			(start -0.508 0.9398)
			(end 0.508 -0.9398)
			(stroke
				(width 0)
				(type default)
			)
			(fill no)
			(layer "F.CrtYd")
		)
		(fp_rect
			(start -0.508 0.9398)
			(end 0.508 -0.9398)
			(stroke
				(width 0)
				(type default)
			)
			(fill no)
			(layer "F.Fab")
		)
		(pad "1" smd custom
			(at 0 -0.4445)
			(size 0.1397 0.1397)
			(layers "F.Cu" "F.Mask" "F.Paste")
			(net "P3V3_STBY_A")
			(options
				(clearance outline)
				(anchor circle)
			)
			(primitives
				(gr_poly
					(pts
						(arc
							(start -0.1778 -0.2794)
							(mid -0.249642 -0.249642)
							(end -0.2794 -0.1778)
						)
						(arc
							(start -0.2794 0.1778)
							(mid -0.249642 0.249642)
							(end -0.1778 0.2794)
						)
						(arc
							(start 0.1778 0.2794)
							(mid 0.249642 0.249642)
							(end 0.2794 0.1778)
						)
						(arc
							(start 0.2794 -0.1778)
							(mid 0.249642 -0.249642)
							(end 0.1778 -0.2794)
						)
					)
					(width 0)
					(fill yes)
				)
			)
		)
		(pad "2" smd custom
			(at 0 0.4445)
			(size 0.1397 0.1397)
			(layers "F.Cu" "F.Mask" "F.Paste")
			(net "I2C_CLIP_A_SCL")
			(options
				(clearance outline)
				(anchor circle)
			)
			(primitives
				(gr_poly
					(pts
						(arc
							(start -0.1778 -0.2794)
							(mid -0.249642 -0.249642)
							(end -0.2794 -0.1778)
						)
						(arc
							(start -0.2794 0.1778)
							(mid -0.249642 0.249642)
							(end -0.1778 0.2794)
						)
						(arc
							(start 0.1778 0.2794)
							(mid 0.249642 0.249642)
							(end 0.2794 0.1778)
						)
						(arc
							(start 0.2794 -0.1778)
							(mid 0.249642 -0.249642)
							(end 0.1778 -0.2794)
						)
					)
					(width 0)
					(fill yes)
				)
			)
		)
	)
	(footprint ""
		(layer "F.Cu")
		(at 351.539302 -158.939992 90)
		(property "Reference" "VIA8"
			(at 0 0 90)
			(layer "F.SilkS")
			(hide yes)
			(effects
				(font
					(size 1.27 1.27)
				)
			)
		)
		(property "Value" "100OHM-8L-1D6MM-L18L16-GP"
			(at -3.7211 -4.5085 90)
			(unlocked yes)
			(layer "F.Fab")
			(hide yes)
			(effects
				(font
					(size 1.016 1.016)
					(thickness 0.1524)
				)
			)
		)
		(property "Device Type" "VIA-PCIE-4P-394076"
			(at -3.7211 -6.0325 90)
			(unlocked yes)
			(layer "F.Fab")
			(hide yes)
			(effects
				(font
					(size 1.016 1.016)
					(thickness 0.1524)
				)
			)
		)
		(duplicate_pad_numbers_are_jumpers no)
		(fp_rect
			(start -1.9685 0.381)
			(end 1.9685 -0.381)
			(stroke
				(width 0)
				(type default)
			)
			(fill no)
			(layer "F.CrtYd")
		)
		(fp_rect
			(start -1.9685 0.381)
			(end 1.9685 -0.381)
			(stroke
				(width 0)
				(type default)
			)
			(fill no)
			(layer "F.Fab")
		)
		(pad "1" thru_hole circle
			(at -1.5875 0 90)
			(size 0.508 0.508)
			(drill 0.254)
			(layers "*.Cu" "*.Mask")
			(remove_unused_layers no)
			(net "GND")
			(clearance 0.127)
			(thermal_gap 0.127)
		)
		(pad "2" thru_hole circle
			(at -0.5715 0 90)
			(size 0.508 0.508)
			(drill 0.254)
			(layers "*.Cu" "*.Mask")
			(remove_unused_layers no)
			(net "PHY_SCC_A_TO_DRV_A_19_DP")
			(clearance 0.127)
			(thermal_gap 0.127)
		)
		(pad "3" thru_hole circle
			(at 0.5715 0 90)
			(size 0.508 0.508)
			(drill 0.254)
			(layers "*.Cu" "*.Mask")
			(remove_unused_layers no)
			(net "PHY_SCC_A_TO_DRV_A_19_DN")
			(clearance 0.127)
			(thermal_gap 0.127)
		)
		(pad "4" thru_hole circle
			(at 1.5875 0 90)
			(size 0.508 0.508)
			(drill 0.254)
			(layers "*.Cu" "*.Mask")
			(remove_unused_layers no)
			(net "GND")
			(clearance 0.127)
			(thermal_gap 0.127)
		)
	)
	(footprint ""
		(layer "F.Cu")
		(at 314.471304 -245.357142 -90)
		(property "Reference" "R477"
			(at 0 0 270)
			(layer "F.SilkS")
			(hide yes)
			(effects
				(font
					(size 1.27 1.27)
				)
			)
		)
		(property "Value" "4K7R2J-2-GP"
			(at 0.064008 -3.993896 270)
			(unlocked yes)
			(layer "F.Fab")
			(hide yes)
			(effects
				(font
					(size 1.016 1.016)
					(thickness 0.1524)
				)
			)
		)
		(property "Device Type" "R402H16"
			(at 0.064008 -5.517896 270)
			(unlocked yes)
			(layer "F.Fab")
			(hide yes)
			(effects
				(font
					(size 1.016 1.016)
					(thickness 0.1524)
				)
			)
		)
		(duplicate_pad_numbers_are_jumpers no)
		(fp_line
			(start -0.508 -0.9398)
			(end -0.508 0.9398)
			(stroke
				(width 0.1524)
				(type default)
			)
			(layer "F.SilkS")
		)
		(fp_line
			(start 0.508 -0.9398)
			(end -0.508 -0.9398)
			(stroke
				(width 0.1524)
				(type default)
			)
			(layer "F.SilkS")
		)
		(fp_rect
			(start -0.508 0.9398)
			(end 0.508 -0.9398)
			(stroke
				(width 0)
				(type default)
			)
			(fill no)
			(layer "F.CrtYd")
		)
		(fp_rect
			(start -0.508 0.9398)
			(end 0.508 -0.9398)
			(stroke
				(width 0)
				(type default)
			)
			(fill no)
			(layer "F.Fab")
		)
		(pad "1" smd custom
			(at 0 -0.4445 270)
			(size 0.1397 0.1397)
			(layers "F.Cu" "F.Mask" "F.Paste")
			(net "DRIVE_A_6_ACT")
			(options
				(clearance outline)
				(anchor circle)
			)
			(primitives
				(gr_poly
					(pts
						(arc
							(start -0.1778 -0.2794)
							(mid -0.249642 -0.249642)
							(end -0.2794 -0.1778)
						)
						(arc
							(start -0.2794 0.1778)
							(mid -0.249642 0.249642)
							(end -0.1778 0.2794)
						)
						(arc
							(start 0.1778 0.2794)
							(mid 0.249642 0.249642)
							(end 0.2794 0.1778)
						)
						(arc
							(start 0.2794 -0.1778)
							(mid 0.249642 -0.249642)
							(end 0.1778 -0.2794)
						)
					)
					(width 0)
					(fill yes)
				)
			)
		)
		(pad "2" smd custom
			(at 0 0.4445 270)
			(size 0.1397 0.1397)
			(layers "F.Cu" "F.Mask" "F.Paste")
			(net "GND")
			(options
				(clearance outline)
				(anchor circle)
			)
			(primitives
				(gr_poly
					(pts
						(arc
							(start -0.1778 -0.2794)
							(mid -0.249642 -0.249642)
							(end -0.2794 -0.1778)
						)
						(arc
							(start -0.2794 0.1778)
							(mid -0.249642 0.249642)
							(end -0.1778 0.2794)
						)
						(arc
							(start 0.1778 0.2794)
							(mid 0.249642 0.249642)
							(end 0.2794 0.1778)
						)
						(arc
							(start 0.2794 -0.1778)
							(mid 0.249642 -0.249642)
							(end 0.1778 -0.2794)
						)
					)
					(width 0)
					(fill yes)
				)
			)
		)
	)
	(footprint ""
		(layer "F.Cu")
		(at 252.220476 -256.88036)
		(property "Reference" "C18"
			(at 0 0 0)
			(layer "F.SilkS")
			(hide yes)
			(effects
				(font
					(size 1.27 1.27)
				)
			)
		)
		(property "Value" "SCD1U16V2KX-3GP"
			(at 1.1811 -2.7051 0)
			(unlocked yes)
			(layer "F.Fab")
			(hide yes)
			(effects
				(font
					(size 1.016 1.016)
					(thickness 0.1524)
				)
			)
		)
		(property "Device Type" "C402H22"
			(at 1.1811 -4.2291 0)
			(unlocked yes)
			(layer "F.Fab")
			(hide yes)
			(effects
				(font
					(size 1.016 1.016)
					(thickness 0.1524)
				)
			)
		)
		(duplicate_pad_numbers_are_jumpers no)
		(fp_rect
			(start -0.4318 0.9525)
			(end 0.4318 -0.9525)
			(stroke
				(width 0)
				(type default)
			)
			(fill no)
			(layer "F.CrtYd")
		)
		(fp_rect
			(start -0.4318 0.9525)
			(end 0.4318 -0.9525)
			(stroke
				(width 0)
				(type default)
			)
			(fill no)
			(layer "F.Fab")
		)
		(pad "1" smd custom
			(at 0 -0.4445)
			(size 0.1524 0.1524)
			(layers "F.Cu" "F.Mask" "F.Paste")
			(net "P3V3_STBY_A")
			(options
				(clearance outline)
				(anchor circle)
			)
			(primitives
				(gr_poly
					(pts
						(arc
							(start 0.3048 -0.2032)
							(mid 0.275042 -0.275042)
							(end 0.2032 -0.3048)
						)
						(arc
							(start -0.2032 -0.3048)
							(mid -0.275042 -0.275042)
							(end -0.3048 -0.2032)
						)
						(arc
							(start -0.3048 0.2032)
							(mid -0.275042 0.275042)
							(end -0.2032 0.3048)
						)
						(arc
							(start 0.2032 0.3048)
							(mid 0.275042 0.275042)
							(end 0.3048 0.2032)
						)
					)
					(width 0)
					(fill yes)
				)
			)
		)
		(pad "2" smd custom
			(at 0 0.4445)
			(size 0.1524 0.1524)
			(layers "F.Cu" "F.Mask" "F.Paste")
			(net "GND")
			(options
				(clearance outline)
				(anchor circle)
			)
			(primitives
				(gr_poly
					(pts
						(arc
							(start 0.3048 -0.2032)
							(mid 0.275042 -0.275042)
							(end 0.2032 -0.3048)
						)
						(arc
							(start -0.2032 -0.3048)
							(mid -0.275042 -0.275042)
							(end -0.3048 -0.2032)
						)
						(arc
							(start -0.3048 0.2032)
							(mid -0.275042 0.275042)
							(end -0.2032 0.3048)
						)
						(arc
							(start 0.2032 0.3048)
							(mid 0.275042 0.275042)
							(end 0.3048 0.2032)
						)
					)
					(width 0)
					(fill yes)
				)
			)
		)
	)
	(footprint ""
		(layer "F.Cu")
		(at 109.467396 -160.608518 90)
		(property "Reference" "R489"
			(at 0 0 90)
			(layer "F.SilkS")
			(hide yes)
			(effects
				(font
					(size 1.27 1.27)
				)
			)
		)
		(property "Value" "4K7R2J-2-GP"
			(at 0.064008 -3.993896 90)
			(unlocked yes)
			(layer "F.Fab")
			(hide yes)
			(effects
				(font
					(size 1.016 1.016)
					(thickness 0.1524)
				)
			)
		)
		(property "Device Type" "R402H16"
			(at 0.064008 -5.517896 90)
			(unlocked yes)
			(layer "F.Fab")
			(hide yes)
			(effects
				(font
					(size 1.016 1.016)
					(thickness 0.1524)
				)
			)
		)
		(duplicate_pad_numbers_are_jumpers no)
		(fp_line
			(start 0.508 -0.9398)
			(end -0.508 -0.9398)
			(stroke
				(width 0.1524)
				(type default)
			)
			(layer "F.SilkS")
		)
		(fp_line
			(start -0.508 -0.9398)
			(end -0.508 0.9398)
			(stroke
				(width 0.1524)
				(type default)
			)
			(layer "F.SilkS")
		)
		(fp_rect
			(start -0.508 0.9398)
			(end 0.508 -0.9398)
			(stroke
				(width 0)
				(type default)
			)
			(fill no)
			(layer "F.CrtYd")
		)
		(fp_rect
			(start -0.508 0.9398)
			(end 0.508 -0.9398)
			(stroke
				(width 0)
				(type default)
			)
			(fill no)
			(layer "F.Fab")
		)
		(pad "1" smd custom
			(at 0 -0.4445 90)
			(size 0.1397 0.1397)
			(layers "F.Cu" "F.Mask" "F.Paste")
			(net "P12V_A")
			(options
				(clearance outline)
				(anchor circle)
			)
			(primitives
				(gr_poly
					(pts
						(arc
							(start -0.1778 -0.2794)
							(mid -0.249642 -0.249642)
							(end -0.2794 -0.1778)
						)
						(arc
							(start -0.2794 0.1778)
							(mid -0.249642 0.249642)
							(end -0.1778 0.2794)
						)
						(arc
							(start 0.1778 0.2794)
							(mid 0.249642 0.249642)
							(end 0.2794 0.1778)
						)
						(arc
							(start 0.2794 -0.1778)
							(mid 0.249642 -0.249642)
							(end 0.1778 -0.2794)
						)
					)
					(width 0)
					(fill yes)
				)
			)
		)
		(pad "2" smd custom
			(at 0 0.4445 90)
			(size 0.1397 0.1397)
			(layers "F.Cu" "F.Mask" "F.Paste")
			(net "SW_HDD_R15")
			(options
				(clearance outline)
				(anchor circle)
			)
			(primitives
				(gr_poly
					(pts
						(arc
							(start -0.1778 -0.2794)
							(mid -0.249642 -0.249642)
							(end -0.2794 -0.1778)
						)
						(arc
							(start -0.2794 0.1778)
							(mid -0.249642 0.249642)
							(end -0.1778 0.2794)
						)
						(arc
							(start 0.1778 0.2794)
							(mid 0.249642 0.249642)
							(end 0.2794 0.1778)
						)
						(arc
							(start 0.2794 -0.1778)
							(mid 0.249642 -0.249642)
							(end 0.1778 -0.2794)
						)
					)
					(width 0)
					(fill yes)
				)
			)
		)
	)
	(footprint ""
		(layer "F.Cu")
		(at 98.897948 -291.127942 90)
		(property "Reference" "C70"
			(at 0 0 90)
			(layer "F.SilkS")
			(hide yes)
			(effects
				(font
					(size 1.27 1.27)
				)
			)
		)
		(property "Value" "SCD01U50V2KX-1GP"
			(at 1.1811 -2.7051 90)
			(unlocked yes)
			(layer "F.Fab")
			(hide yes)
			(effects
				(font
					(size 1.016 1.016)
					(thickness 0.1524)
				)
			)
		)
		(property "Device Type" "C402H22"
			(at 1.1811 -4.2291 90)
			(unlocked yes)
			(layer "F.Fab")
			(hide yes)
			(effects
				(font
					(size 1.016 1.016)
					(thickness 0.1524)
				)
			)
		)
		(duplicate_pad_numbers_are_jumpers no)
		(fp_rect
			(start -0.4318 0.9525)
			(end 0.4318 -0.9525)
			(stroke
				(width 0)
				(type default)
			)
			(fill no)
			(layer "F.CrtYd")
		)
		(fp_rect
			(start -0.4318 0.9525)
			(end 0.4318 -0.9525)
			(stroke
				(width 0)
				(type default)
			)
			(fill no)
			(layer "F.Fab")
		)
		(pad "1" smd custom
			(at 0 -0.4445 90)
			(size 0.1524 0.1524)
			(layers "F.Cu" "F.Mask" "F.Paste")
			(net "HDD_PRSNT_2")
			(options
				(clearance outline)
				(anchor circle)
			)
			(primitives
				(gr_poly
					(pts
						(arc
							(start 0.3048 -0.2032)
							(mid 0.275042 -0.275042)
							(end 0.2032 -0.3048)
						)
						(arc
							(start -0.2032 -0.3048)
							(mid -0.275042 -0.275042)
							(end -0.3048 -0.2032)
						)
						(arc
							(start -0.3048 0.2032)
							(mid -0.275042 0.275042)
							(end -0.2032 0.3048)
						)
						(arc
							(start 0.2032 0.3048)
							(mid 0.275042 0.275042)
							(end 0.3048 0.2032)
						)
					)
					(width 0)
					(fill yes)
				)
			)
		)
		(pad "2" smd custom
			(at 0 0.4445 90)
			(size 0.1524 0.1524)
			(layers "F.Cu" "F.Mask" "F.Paste")
			(net "GND")
			(options
				(clearance outline)
				(anchor circle)
			)
			(primitives
				(gr_poly
					(pts
						(arc
							(start 0.3048 -0.2032)
							(mid 0.275042 -0.275042)
							(end 0.2032 -0.3048)
						)
						(arc
							(start -0.2032 -0.3048)
							(mid -0.275042 -0.275042)
							(end -0.3048 -0.2032)
						)
						(arc
							(start -0.3048 0.2032)
							(mid -0.275042 0.275042)
							(end -0.2032 0.3048)
						)
						(arc
							(start 0.2032 0.3048)
							(mid 0.275042 0.275042)
							(end 0.3048 0.2032)
						)
					)
					(width 0)
					(fill yes)
				)
			)
		)
	)
	(footprint ""
		(layer "F.Cu")
		(at 130.175 -298.704)
		(property "Reference" "TP17"
			(at 0 0 0)
			(layer "F.SilkS")
			(hide yes)
			(effects
				(font
					(size 1.27 1.27)
				)
			)
		)
		(property "Value" "TPAD32-GP"
			(at -0.0508 -1.6764 0)
			(unlocked yes)
			(layer "F.Fab")
			(hide yes)
			(effects
				(font
					(size 1.016 1.016)
					(thickness 0.1524)
				)
			)
		)
		(property "Device Type" "TPAD32"
			(at -0.0508 -3.2004 0)
			(unlocked yes)
			(layer "F.Fab")
			(hide yes)
			(effects
				(font
					(size 1.016 1.016)
					(thickness 0.1524)
				)
			)
		)
		(duplicate_pad_numbers_are_jumpers no)
		(fp_poly
			(pts
				(arc
					(start 0.4064 0)
					(mid -0.4064 0)
					(end 0.4064 0)
				)
			)
			(stroke
				(width 0)
				(type default)
			)
			(fill no)
			(layer "F.CrtYd")
		)
		(fp_poly
			(pts
				(arc
					(start 0.7112 0)
					(mid -0.7112 0)
					(end 0.7112 0)
				)
			)
			(stroke
				(width 0)
				(type default)
			)
			(fill no)
			(layer "F.Fab")
		)
		(pad "1" smd circle
			(at 0 0)
			(size 0.8128 0.8128)
			(layers "F.Cu" "F.Mask" "F.Paste")
			(net "ACT_HDD_3")
		)
	)
)
